# BASEBOARD_FAB2 (Tioga Pass) — schematic netlist excerpt (pin names and nets, part order shuffled) for the footprints in the layout excerpt that follows; sources: Cadence DE-HDL packaged netlist, KiCad conversion of Wiwynn_Tioga_Pass_MB.brd

C1U21  CAP  47.0PF 50V 5% COG  pkg 0402LF  page 169 : A = A_P1V05_STBY_PCH_SENSOR ; B = GND
R7W1  RES  0.0 5% CHIP  pkg 0402  page 118 : A = FM_SLPS3_N ; B = FM_SLPS3_R_N
R4G9  RES  6.19K 1% CHIP  pkg 0402  page 233 : A = VR_FB_PVPP_GHJ ; B = AGND_PVPP_GHJ

(kicad_pcb
	(version 20260206)
	(generator "pcbnew")
	(generator_version "10.0")
	(general
		(thickness 1.6)
		(legacy_teardrops no)
	)
	(paper "A4")
	(title_block
		(title "Wiwynn_Tioga_Pass_MB.brd")
		(comment 1 "Tioga Pass / footprints 1591-1593 of 4770")
	)
	(layers
		(0 "F.Cu" signal "TOP")
		(4 "In1.Cu" signal "L2GND")
		(6 "In2.Cu" signal "L3")
		(8 "In3.Cu" signal "L4GND")
		(10 "In4.Cu" signal "L5")
		(12 "In5.Cu" signal "L6GND")
		(14 "In6.Cu" signal "L7VCC")
		(16 "In7.Cu" signal "L8VCC")
		(18 "In8.Cu" signal "L9GND")
		(20 "In9.Cu" signal "L10")
		(22 "In10.Cu" signal "L11GND")
		(24 "In11.Cu" signal "L12")
		(26 "In12.Cu" signal "L13GND")
		(2 "B.Cu" signal "BOTTOM")
		(9 "F.Adhes" user "F.Adhesive")
		(11 "B.Adhes" user "B.Adhesive")
		(13 "F.Paste" user "Package Geometry/Pastemask Top")
		(15 "B.Paste" user "Package Geometry/Pastemask Bottom")
		(5 "F.SilkS" user "Ref Des/Silkscreen Top")
		(7 "B.SilkS" user "Ref Des/Silkscreen Bottom")
		(1 "F.Mask" user "Board Geometry/Soldermask Top")
		(3 "B.Mask" user "Board Geometry/Soldermask Bottom")
		(17 "Dwgs.User" user "User.Drawings")
		(19 "Cmts.User" user "User.Comments")
		(21 "Eco1.User" user "User.Eco1")
		(23 "Eco2.User" user "User.Eco2")
		(25 "Edge.Cuts" user "Board Geometry/Outline")
		(27 "Margin" user)
		(31 "F.CrtYd" user "Package Geometry/Place Bound Top")
		(29 "B.CrtYd" user "Package Geometry/Place Bound Bottom")
		(35 "F.Fab" user "Ref Des/Assembly Top")
		(33 "B.Fab" user "Ref Des/Assembly Bottom")
	)
	(footprint ""
		(layer "F.Cu")
		(at 370.967 -97.155 180)
		(property "Reference" "R7W1"
			(at -0.8382 -0.67818 180)
			(unlocked yes)
			(layer "F.SilkS")
			(effects
				(font
					(size 0.4064 0.254)
					(thickness 0.1524)
				)
				(justify left)
			)
		)
		(property "Value" ""
			(at 0 0 180)
			(layer "F.Fab")
			(effects
				(font
					(size 1.27 1.27)
				)
			)
		)
		(duplicate_pad_numbers_are_jumpers no)
		(fp_poly
			(pts
				(xy -0.2794 -0.1016) (xy 0.2794 -0.1016) (xy 0.2794 0.9906) (xy -0.2794 0.9906)
			)
			(stroke
				(width 0)
				(type default)
			)
			(fill no)
			(layer "F.CrtYd")
		)
		(fp_line
			(start 0.2794 0.9906)
			(end 0.2794 -0.1016)
			(stroke
				(width 0.1)
				(type default)
			)
			(layer "F.Fab")
		)
		(fp_line
			(start 0.2794 -0.1016)
			(end -0.2794 -0.1016)
			(stroke
				(width 0.1)
				(type default)
			)
			(layer "F.Fab")
		)
		(fp_line
			(start -0.2794 0.9906)
			(end 0.2794 0.9906)
			(stroke
				(width 0.1)
				(type default)
			)
			(layer "F.Fab")
		)
		(fp_line
			(start -0.2794 -0.1016)
			(end -0.2794 0.9906)
			(stroke
				(width 0.1)
				(type default)
			)
			(layer "F.Fab")
		)
		(pad "1" smd rect
			(at 0 0 180)
			(size 0.508 0.508)
			(layers "F.Cu" "F.Mask" "F.Paste")
			(net "FM_SLPS3_N")
		)
		(pad "2" smd rect
			(at 0 0.889 180)
			(size 0.508 0.508)
			(layers "F.Cu" "F.Mask" "F.Paste")
			(net "FM_SLPS3_R_N")
		)
		(zone
			(layer "F.Cu")
			(hatch none 0.5)
			(connect_pads
				(clearance 0)
			)
			(min_thickness 0.25)
			(keepout
				(tracks not_allowed)
				(vias allowed)
				(pads allowed)
				(copperpour not_allowed)
				(footprints allowed)
			)
			(placement
				(enabled no)
				(sheetname "")
			)
			(fill
				(thermal_gap 0.5)
				(thermal_bridge_width 0.5)
				(island_removal_mode 0)
			)
			(polygon
				(pts
					(xy 371.221 -97.79) (xy 370.713 -97.79) (xy 370.713 -97.409) (xy 371.221 -97.409)
				)
			)
		)
		(zone
			(layer "F.Cu")
			(hatch none 0.5)
			(connect_pads
				(clearance 0)
			)
			(min_thickness 0.25)
			(keepout
				(tracks allowed)
				(vias not_allowed)
				(pads allowed)
				(copperpour not_allowed)
				(footprints allowed)
			)
			(placement
				(enabled no)
				(sheetname "")
			)
			(fill
				(thermal_gap 0.5)
				(thermal_bridge_width 0.5)
				(island_removal_mode 0)
			)
			(polygon
				(pts
					(xy 371.221 -97.409) (xy 370.713 -97.409) (xy 370.713 -97.79) (xy 371.221 -97.79)
				)
			)
		)
	)
	(footprint ""
		(layer "F.Cu")
		(at 407.67 -20.2565)
		(property "Reference" "C1U21"
			(at 0 0 0)
			(layer "F.SilkS")
			(hide yes)
			(effects
				(font
					(size 1.27 1.27)
				)
			)
		)
		(property "Value" ""
			(at 0 0 0)
			(layer "F.Fab")
			(effects
				(font
					(size 1.27 1.27)
				)
			)
		)
		(duplicate_pad_numbers_are_jumpers no)
		(fp_poly
			(pts
				(xy 0.3048 -0.1016) (xy 0.3048 0.9906) (xy -0.3048 0.9906) (xy -0.3048 -0.1016)
			)
			(stroke
				(width 0)
				(type default)
			)
			(fill no)
			(layer "F.CrtYd")
		)
		(fp_line
			(start -0.3048 -0.1016)
			(end -0.3048 0.9906)
			(stroke
				(width 0.1)
				(type default)
			)
			(layer "F.Fab")
		)
		(fp_line
			(start -0.3048 0.9906)
			(end 0.3048 0.9906)
			(stroke
				(width 0.1)
				(type default)
			)
			(layer "F.Fab")
		)
		(fp_line
			(start 0.3048 -0.1016)
			(end -0.3048 -0.1016)
			(stroke
				(width 0.1)
				(type default)
			)
			(layer "F.Fab")
		)
		(fp_line
			(start 0.3048 0.9906)
			(end 0.3048 -0.1016)
			(stroke
				(width 0.1)
				(type default)
			)
			(layer "F.Fab")
		)
		(pad "1" smd rect
			(at 0 0)
			(size 0.508 0.508)
			(layers "F.Cu" "F.Mask" "F.Paste")
			(net "A_P1V05_STBY_PCH_SENSOR")
		)
		(pad "2" smd rect
			(at 0 0.889)
			(size 0.508 0.508)
			(layers "F.Cu" "F.Mask" "F.Paste")
			(net "GND")
		)
		(zone
			(layer "F.Cu")
			(hatch none 0.5)
			(connect_pads
				(clearance 0)
			)
			(min_thickness 0.25)
			(keepout
				(tracks allowed)
				(vias not_allowed)
				(pads allowed)
				(copperpour not_allowed)
				(footprints allowed)
			)
			(placement
				(enabled no)
				(sheetname "")
			)
			(fill
				(thermal_gap 0.5)
				(thermal_bridge_width 0.5)
				(island_removal_mode 0)
			)
			(polygon
				(pts
					(xy 407.416 -20.0025) (xy 407.924 -20.0025) (xy 407.924 -19.6215) (xy 407.416 -19.6215)
				)
			)
		)
		(zone
			(layer "F.Cu")
			(hatch none 0.5)
			(connect_pads
				(clearance 0)
			)
			(min_thickness 0.25)
			(keepout
				(tracks not_allowed)
				(vias allowed)
				(pads allowed)
				(copperpour not_allowed)
				(footprints allowed)
			)
			(placement
				(enabled no)
				(sheetname "")
			)
			(fill
				(thermal_gap 0.5)
				(thermal_bridge_width 0.5)
				(island_removal_mode 0)
			)
			(polygon
				(pts
					(xy 407.416 -19.6215) (xy 407.924 -19.6215) (xy 407.924 -20.0025) (xy 407.416 -20.0025)
				)
			)
		)
	)
	(footprint ""
		(layer "F.Cu")
		(at 174.244 -8.6995)
		(property "Reference" "R4G9"
			(at 0 0 0)
			(layer "F.SilkS")
			(hide yes)
			(effects
				(font
					(size 1.27 1.27)
				)
			)
		)
		(property "Value" ""
			(at 0 0 0)
			(layer "F.Fab")
			(effects
				(font
					(size 1.27 1.27)
				)
			)
		)
		(duplicate_pad_numbers_are_jumpers no)
		(fp_rect
			(start -0.2794 0.9906)
			(end 0.2794 -0.1016)
			(stroke
				(width 0)
				(type default)
			)
			(fill no)
			(layer "F.CrtYd")
		)
		(fp_line
			(start -0.2794 -0.1016)
			(end -0.2794 0.9906)
			(stroke
				(width 0.1)
				(type default)
			)
			(layer "F.Fab")
		)
		(fp_line
			(start -0.2794 0.9906)
			(end 0.2794 0.9906)
			(stroke
				(width 0.1)
				(type default)
			)
			(layer "F.Fab")
		)
		(fp_line
			(start 0.2794 -0.1016)
			(end -0.2794 -0.1016)
			(stroke
				(width 0.1)
				(type default)
			)
			(layer "F.Fab")
		)
		(fp_line
			(start 0.2794 0.9906)
			(end 0.2794 -0.1016)
			(stroke
				(width 0.1)
				(type default)
			)
			(layer "F.Fab")
		)
		(pad "1" smd rect
			(at 0 0)
			(size 0.508 0.508)
			(layers "F.Cu" "F.Mask" "F.Paste")
			(net "VR_FB_PVPP_GHJ")
		)
		(pad "2" smd rect
			(at 0 0.889)
			(size 0.508 0.508)
			(layers "F.Cu" "F.Mask" "F.Paste")
			(net "AGND_PVPP_GHJ")
		)
		(zone
			(layer "F.Cu")
			(hatch none 0.5)
			(connect_pads
				(clearance 0)
			)
			(min_thickness 0.25)
			(keepout
				(tracks not_allowed)
				(vias allowed)
				(pads allowed)
				(copperpour not_allowed)
				(footprints allowed)
			)
			(placement
				(enabled no)
				(sheetname "")
			)
			(fill
				(thermal_gap 0.5)
				(thermal_bridge_width 0.5)
				(island_removal_mode 0)
			)
			(polygon
				(pts
					(xy 173.99 -8.0645) (xy 174.498 -8.0645) (xy 174.498 -8.4455) (xy 173.99 -8.4455)
				)
			)
		)
		(zone
			(layer "F.Cu")
			(hatch none 0.5)
			(connect_pads
				(clearance 0)
			)
			(min_thickness 0.25)
			(keepout
				(tracks allowed)
				(vias not_allowed)
				(pads allowed)
				(copperpour not_allowed)
				(footprints allowed)
			)
			(placement
				(enabled no)
				(sheetname "")
			)
			(fill
				(thermal_gap 0.5)
				(thermal_bridge_width 0.5)
				(island_removal_mode 0)
			)
			(polygon
				(pts
					(xy 173.99 -8.0645) (xy 174.498 -8.0645) (xy 174.498 -8.4455) (xy 173.99 -8.4455)
				)
			)
		)
	)
)
